FILE_TYPE = CONNECTIVITY;
{Allegro Design Entry HDL 16.6-p007 (v16-6-112F) 10/10/2012}
"PAGE_NUMBER" = 211;
0"NC";
1"GND\g";
2"GND\g";
3"PVCCIO_CPU0\g";
4"GND\g";
5"GND\g";
6"GND\g";
7"P3V3_STBY\g";
8"PVCCIO_CPU0\g";
9"VR_FET_SW_P12V_STBY_PVCCIO_CPU0\g";
10"GND\g";
11"GND\g";
12"GND\g";
13"GND\g";
14"P3V3_STBY\g";
15"GND\g";
16"GND\g";
17"SVID_CLK0_CPU0_R";
18"SVID_DIO0_CPU0_R";
19"VR_PVCCIO_CPU0_AIREF1";
20"VR_PVCCIO_CPU0_XADDR2"VOLTAGE"3.3V";
21"SVID_CLK_PVCCIO_CPU0";
22"VR_PVCCIO_CPU0_EN";
23"ISENSE_PVCCIO_CPU0_PH1_IMON";
24"SVID_ALERT_PVCCIO_CPU0";
25"IRQ_PVCCIO_CPU0_VRHOT_N";
26"A_TSENSE_PVCCIO_CPU0"VOLTAGE"3.6";
27"VR_PVCCIO_CPU0_VINSEN";
28"VR_PVCCIO_CPU0_VD12";
29"VR_PVCCIO_CPU0_AVSP"VOLTAGE"2";
30"VR_PVCCIO_CPU0_VINSEN"VOLTAGE"0.8";
31"SVID_VDIO_PVCCIO_CPU0";
32"PWRGD_PVCCIO_CPU0";
33"SVID_ALERT0_CPU0_R_N";
34"VR_PVCCIO_CPU0_PWM1"VOLTAGE"3.3";
35"PU_VR_PVCCIO_CPU0_FAULT1";
36"PWRGD_PVCCIO_CPU0_R";
37"VR_PVCCIO_CPU0_XADDR1"VOLTAGE"3.3";
38"VSENSE_PVCCIO_CPU0_AVSN";
39"SMB_VR_STBY_LVC3_SDA";
40"SMB_VR_STBY_LVC3_SCL";
41"VR_PVCCIO_CPU0_VD12";
42"VSENSE_PVCCIO_CPU0_AVSP";
43"FM_PVCCIO_CPU0_EN";
44"VR_PVCCIO_CPU0_VDD";
%"RES"
"2","(-1600,4500)","0","mstr_discrete","I100";
;
WATTAGE"1/16W"
MATERIAL"CHIP"
VALUE"100.0"
TOLERANCE"1%"
LOCATION"R3P13"
PART_NUMBER"G21796-017"
PACK_TYPE"0402"
CDS_SEC"1"
CDS_LIB"mstr_discrete"
ROOM"PVCCIN_CPU0_VR"
SEC_TYPE"0402"
SEC"1"
CDS_LOCATION"R3P13";
"A"
$PN"1"3;
"B"
$PN"2"18;
%"RES"
"2","(-575,1200)","0","mstr_discrete","I102";
;
CDS_SEC"1"
MATERIAL"CHIP"
TOLERANCE"1%"
WATTAGE"1/16W"
LOCATION"R3N22"
VALUE"4.02K"
PACK_TYPE"0402"
PART_NUMBER"G21796-082"
SEC_TYPE"0402"
SEC"1"
ROOM"PVCCIN_CPU0_VR"
CDS_LIB"mstr_discrete"
CDS_LOCATION"R3N22";
"A"
$PN"1"20;
"B"
$PN"2"13;
%"CAP_A"
"1","(-2850,4300)","0","dev_discrete","I103";
;
MATERIAL"X7R"
LOCATION"C3P2"
VALUE"0.1UF"
VOLTAGE"16V"
PART_NUMBER"A36096-030"
TOLERANCE"10%"
PACK_TYPE"0402V"
CDS_LOCATION"C3P2"
CDS_LIB"dev_discrete"
BOM_COST"SM_THERM"
ROOM"CPU_FANS"
SEC_TYPE"0402V"
SEC"1"
CDS_SEC"1";
"B"
$PN"2"11;
"A"
$PN"1"30;
%"CAP_A"
"1","(2475,1425)","0","dev_discrete","I11";
;
LOCATION"C3P4"
PART_NUMBER"D97712-004"
VALUE"1.0UF"
TOLERANCE"10%"
PACK_TYPE"0402V"
VOLTAGE"6.3V"
MATERIAL"X6S"
ROOM"PVCCIO_CPU0"
SEC"1"
SEC_TYPE"0402V"
CDS_SEC"1"
CDS_LOCATION"C3P4"
CDS_LIB"dev_discrete";
"B"
$PN"2"1;
"A"
$PN"1"41;
%"GND"
"1","(2475,1100)","0","mstr_symbols","I12";
;
HDL_POWER"GND"
BODY_TYPE"PLUMBING"
VOLTAGE"0"
SIZE"1B"
CDS_LIB"mstr_symbols"
ROOM"PVCCIO_CPU0";
"A\NAC"1;
%"CAP_A"
"1","(2075,1425)","0","dev_discrete","I13";
;
PART_NUMBER"A36096-030"
VALUE"0.1UF"
VOLTAGE"16V"
TOLERANCE"10%"
PACK_TYPE"0402V"
LOCATION"C3P5"
MATERIAL"X7R"
SEC"1"
SEC_TYPE"0402V"
CDS_SEC"1"
ROOM"PVCCIO_CPU0"
CDS_LOCATION"C3P5"
CDS_LIB"dev_discrete";
"B"
$PN"2"2;
"A"
$PN"1"41;
%"GND"
"1","(2075,1225)","0","mstr_symbols","I14";
;
HDL_POWER"GND"
BODY_TYPE"PLUMBING"
CDS_LIB"mstr_symbols"
SIZE"1B"
VOLTAGE"0"
ROOM"PVCCIO_CPU0";
"A\NAC"2;
%"RES"
"1","(-1250,2950)","0","mstr_discrete","I16";
;
CDS_SEC"1"
PART_NUMBER"G21497-005"
VALUE"0.0"
MATERIAL"CHIP"
PACK_TYPE"0402"
LOCATION"R3P11"
TOLERANCE"5%"
WATTAGE"1/16W"
SEC_TYPE"0402"
SEC"1"
ROOM"PVCCIO_CPU0"
CDS_LIB"mstr_discrete"
CDS_LOCATION"R3P11";
"B"
$PN"2"31;
"A"
$PN"1"18;
%"PVCCIO_CPU0"
"1","(-1600,4825)","0","mstr_symbols","I18";
;
HDL_POWER"PVCCIO_CPU0"
BODY_TYPE"PLUMBING"
VOLTAGE"1.1V"
CDS_LIB"mstr_symbols";
"G\NAC"3;
%"GND"
"1","(925,1900)","0","mstr_symbols","I2";
;
HDL_POWER"GND"
BODY_TYPE"PLUMBING"
ROOM"PVCCIO_CPU0"
CDS_LIB"mstr_symbols"
SIZE"1B"
VOLTAGE"0";
"A\NAC"4;
%"CAP_A"
"1","(75,4175)","0","dev_discrete","I20";
;
CDS_SEC"1"
VOLTAGE"6.3V"
TOLERANCE"10%"
MATERIAL"X6S"
PART_NUMBER"D97712-004"
PACK_TYPE"0402V"
VALUE"1.0UF"
LOCATION"C3P3"
SEC_TYPE"0402V"
SEC"1"
ROOM"PVCCIO_CPU0"
CDS_LOCATION"C3P3"
CDS_LIB"dev_discrete";
"B"
$PN"2"5;
"A"
$PN"1"44;
%"GND"
"1","(75,3975)","0","mstr_symbols","I21";
;
HDL_POWER"GND"
BODY_TYPE"PLUMBING"
SIZE"1B"
VOLTAGE"0"
CDS_LIB"mstr_symbols"
ROOM"PVCCIO_CPU0";
"A\NAC"5;
%"CAP_A"
"1","(-325,4175)","0","dev_discrete","I22";
;
TOLERANCE"10%"
VOLTAGE"16V"
MATERIAL"X7R"
PART_NUMBER"A36096-030"
PACK_TYPE"0402V"
LOCATION"C3P7"
VALUE"0.1UF"
SEC_TYPE"0402V"
SEC"1"
CDS_SEC"1"
ROOM"PVCCIO_CPU0"
CDS_LOCATION"C3P7"
CDS_LIB"dev_discrete";
"B"
$PN"2"6;
"A"
$PN"1"44;
%"GND"
"1","(-325,3975)","0","mstr_symbols","I23";
;
HDL_POWER"GND"
BODY_TYPE"PLUMBING"
ROOM"PVCCIO_CPU0"
SIZE"1B"
VOLTAGE"0"
CDS_LIB"mstr_symbols";
"A\NAC"6;
%"RES"
"2","(-625,4525)","0","mstr_discrete","I24";
;
CDS_SEC"1"
LOCATION"R3P22"
PART_NUMBER"G21497-005"
VALUE"0.0"
PACK_TYPE"0402"
MATERIAL"CHIP"
WATTAGE"1/16W"
TOLERANCE"5%"
SEC_TYPE"0402"
ROOM"PVCCIO_CPU0"
SEC"1"
CDS_LOCATION"R3P22"
CDS_LIB"mstr_discrete";
"A"
$PN"1"7;
"B"
$PN"2"44;
%"P3V3_STBY"
"1","(-625,4850)","0","mstr_symbols","I25";
;
HDL_POWER"P3V3_STBY"
BODY_TYPE"PLUMBING"
SIZE"1B"
CDS_LIB"mstr_symbols"
VOLTAGE"3.3V";
"G\NAC"7;
%"PVCCIO_CPU0"
"1","(-2125,4875)","0","mstr_symbols","I27";
;
HDL_POWER"PVCCIO_CPU0"
BODY_TYPE"PLUMBING"
CDS_LIB"mstr_symbols"
VOLTAGE"1.1V";
"G\NAC"8;
%"RES"
"1","(-1975,3975)","0","mstr_discrete","I29";
;
CDS_SEC"1"
PACK_TYPE"0402"
WATTAGE"1/16W"
LOCATION"R3P15"
TOLERANCE"1%"
MATERIAL"CHIP"
VALUE"150.0"
PART_NUMBER"G21796-009"
SEC_TYPE"0402"
SEC"1"
CDS_LOCATION"R3P15"
ROOM"PVCCIO_CPU0"
CDS_LIB"mstr_discrete";
"B"
$PN"2"21;
"A"
$PN"1"17;
%"VCC_CORE"
"1","(-2500,4850)","0","mstr_symbols","I30";
;
HDL_POWER"VR_FET_SW_P12V_STBY_PVCCIO_CPU0"
CDS_LIB"mstr_symbols";
"A"9;
%"RES"
"2","(-2500,4650)","0","mstr_discrete","I31";
;
CDS_SEC"1"
PART_NUMBER"G21796-160"
MATERIAL"CHIP"
WATTAGE"1/16W"
LOCATION"R3P12"
VALUE"100.0K"
PACK_TYPE"0402"
TOLERANCE"1%"
SEC_TYPE"0402"
SEC"1"
NO_XNET_CONNECTION"1"
ROOM"PVCCIO_CPU0"
CDS_LIB"mstr_discrete"
CDS_LOCATION"R3P12";
"A"
$PN"1"9;
"B"
$PN"2"30;
%"RES"
"2","(-2500,4300)","0","mstr_discrete","I32";
;
CDS_SEC"1"
WATTAGE"1/16W"
VALUE"1.5K"
LOCATION"R3P16"
PACK_TYPE"0402"
MATERIAL"CHIP"
TOLERANCE"1%"
PART_NUMBER"G21796-003"
SEC_TYPE"0402"
SEC"1"
ROOM"PVCCIO_CPU0"
CDS_LIB"mstr_discrete"
CDS_LOCATION"R3P16";
"A"
$PN"1"30;
"B"
$PN"2"10;
%"GND"
"1","(-2500,4100)","0","mstr_symbols","I34";
;
HDL_POWER"GND"
BODY_TYPE"PLUMBING"
VOLTAGE"0"
CDS_LIB"mstr_symbols"
ROOM"PVCCIO_CPU0"
SIZE"1B";
"A\NAC"10;
%"GND"
"1","(-2850,4100)","0","mstr_symbols","I35";
;
SIZE"1B"
CDS_LIB"mstr_symbols"
VOLTAGE"0"
ROOM"PVCCIO_CPU0"
BODY_TYPE"PLUMBING"
HDL_POWER"GND";
"A\NAC"11;
%"GND"
"1","(-1025,2050)","0","mstr_symbols","I51";
;
HDL_POWER"GND"
BODY_TYPE"PLUMBING"
CDS_LIB"mstr_symbols"
VOLTAGE"0"
ROOM"PVCCIO_CPU0"
SIZE"1B";
"A\NAC"12;
%"RES"
"2","(-925,1200)","0","mstr_discrete","I52";
;
CDS_SEC"1"
CDS_LOCATION"R3N31"
VALUE"3.16K"
TOLERANCE"1%"
MATERIAL"CHIP"
WATTAGE"1/16W"
LOCATION"R3N31"
PART_NUMBER"G21796-043"
PACK_TYPE"0402"
ROOM"PVCCIO_CPU0"
CDS_LIB"mstr_discrete"
SEC_TYPE"0402"
SEC"1";
"A"
$PN"1"37;
"B"
$PN"2"13;
%"GND"
"1","(-925,750)","0","mstr_symbols","I54";
;
ROOM"PVCCIO_CPU0"
VOLTAGE"0"
SIZE"1B"
CDS_LIB"mstr_symbols"
BODY_TYPE"PLUMBING"
HDL_POWER"GND";
"A\NAC"13;
%"RES"
"2","(775,4100)","0","mstr_discrete","I56";
;
CDS_SEC"1"
VALUE"1.00K"
TOLERANCE"1%"
LOCATION"R3P25"
WATTAGE"1/16W"
PART_NUMBER"G21796-026"
MATERIAL"CHIP"
PACK_TYPE"0402"
SEC_TYPE"0402"
SEC"1"
ROOM"PVCCIO_CPU0"
CDS_LIB"mstr_discrete"
CDS_LOCATION"R3P25";
"A"
$PN"1"14;
"B"
$PN"2"36;
%"RES"
"1","(1875,3600)","0","mstr_discrete","I58";
;
CDS_SEC"1"
TOLERANCE"1.0%"
VALUE"22.1"
PART_NUMBER"G21796-250"
LOCATION"R3P20"
WATTAGE"1/16W"
MATERIAL"CHIP"
PACK_TYPE"0402"
SEC_TYPE"0402"
ROOM"PVCCIO_CPU0"
CDS_LIB"mstr_discrete"
SEC"1"
CDS_LOCATION"R3P20";
"B"
$PN"2"32;
"A"
$PN"1"36;
%"P3V3_STBY"
"1","(1800,4775)","0","mstr_symbols","I59";
;
HDL_POWER"P3V3_STBY"
BODY_TYPE"PLUMBING"
VOLTAGE"3.3V"
CDS_LIB"mstr_symbols"
SIZE"1B";
"G\NAC"14;
%"RES"
"2","(1525,4100)","0","mstr_discrete","I60";
;
CDS_SEC"1"
TOLERANCE"1.0%"
VALUE"2.26K"
LOCATION"R3N23"
WATTAGE"1/16W"
PART_NUMBER"G21796-311"
PACK_TYPE"0402"
MATERIAL"EMPTY"
SEC"1"
CDS_LOCATION"R3N23"
SEC_TYPE"0402"
CDS_LIB"mstr_discrete"
ROOM"PVCCIO_CPU0";
"A"
$PN"1"14;
"B"
$PN"2"35;
%"RES"
"1","(1375,3150)","0","mstr_discrete","I61";
;
CDS_SEC"1"
LOCATION"R3P1"
WATTAGE"1/16W"
VALUE"0.0"
PART_NUMBER"G21497-005"
MATERIAL"CHIP"
PACK_TYPE"0402"
TOLERANCE"5%"
SEC_TYPE"0402"
CDS_LOCATION"R3P1"
SEC"1"
ROOM"PVCCIO_CPU0"
CDS_LIB"mstr_discrete";
"B"
$PN"2"33;
"A"
$PN"1"24;
%"RES"
"2","(2075,4050)","0","mstr_discrete","I64";
;
CDS_SEC"1"
LOCATION"R3P18"
TOLERANCE"1%"
MATERIAL"CHIP"
VALUE"1.00K"
WATTAGE"1/16W"
PACK_TYPE"0402"
PART_NUMBER"G21796-026"
SEC_TYPE"0402"
SEC"1"
CDS_LOCATION"R3P18"
CDS_LIB"mstr_discrete";
"A"
$PN"1"14;
"B"
$PN"2"25;
%"CAP"
"1","(1650,2750)","0","mstr_discrete","I71";
;
CDS_SEC"1"
VOLTAGE"50V"
PACK_TYPE"0402LF"
LOCATION"C3P6"
TOLERANCE"10%"
MATERIAL"X7R"
VALUE"1000PF"
PART_NUMBER"A36096-046"
ROOM"PVCCIO_CPU0_VR"
SEC"1"
SEC_TYPE"0402LF"
CDS_LOCATION"C3P6"
CDS_LIB"mstr_discrete";
"A"
$PN"1"36;
"B"
$PN"2"15;
%"GND"
"1","(1650,2475)","0","mstr_symbols","I72";
;
HDL_POWER"GND"
BODY_TYPE"PLUMBING"
VOLTAGE"0"
CDS_LIB"mstr_symbols"
SIZE"1B"
ROOM"PVCCIO_CPU0";
"A\NAC"15;
%"RES"
"1","(-2600,2050)","0","mstr_discrete","I81";
;
CDS_SEC"1"
PACK_TYPE"0402"
PART_NUMBER"G21796-066"
MATERIAL"CHIP"
VALUE"10.0"
LOCATION"R3N19"
TOLERANCE"1%"
WATTAGE"1/16W"
SEC_TYPE"0402"
SEC"1"
ROOM"PVCCIO_CPU0"
CDS_LIB"mstr_discrete"
CDS_LOCATION"R3N19";
"B"
$PN"2"29;
"A"
$PN"1"42;
%"CAP"
"1","(-2400,1850)","0","mstr_discrete","I83";
;
CDS_SEC"1"
VALUE"220PF"
MATERIAL"X7R"
TOLERANCE"10%"
PART_NUMBER"A36096-050"
PACK_TYPE"0402LF"
VOLTAGE"50V"
LOCATION"C3N39"
SEC"1"
SEC_TYPE"0402LF"
ROOM"PVCCIO_CPU0"
CDS_LOCATION"C3N39"
CDS_LIB"mstr_discrete";
"A"
$PN"1"29;
"B"
$PN"2"38;
%"RES"
"1","(-1950,3250)","0","mstr_discrete","I87";
;
CDS_SEC"1"
PART_NUMBER"G21497-005"
WATTAGE"1/16W"
LOCATION"R3P26"
PACK_TYPE"0402"
TOLERANCE"5%"
VALUE"0.0"
MATERIAL"CHIP"
SEC_TYPE"0402"
SEC"1"
ROOM"PVCCIN_CPU0_VR"
CDS_LOCATION"R3P26"
CDS_LIB"mstr_discrete";
"B"
$PN"2"22;
"A"
$PN"1"43;
%"RES"
"2","(-1125,4300)","0","mstr_discrete","I88";
;
TOLERANCE"1%"
PART_NUMBER"G21796-010"
PACK_TYPE"0402"
LOCATION"R3P21"
MATERIAL"EMPTY"
WATTAGE"1/16W"
VALUE"100.0K"
BOM_COST"SM_CONTROLLER"
CDS_SEC"1"
$SEC"1"
CDS_LOCATION"R3P21"
ROOM"BMC"
CDS_LIB"mstr_discrete";
"A"
$PN"1"7;
"B"
$PN"2"22;
%"PXE1110B"
"1","(100,2850)","0","mstr_controller","I93";
;
CDS_SEC"1"
LOCATION"EU3P1"
MATERIAL"IC"
PART_NUMBER"H89187-001"
CDS_LMAN_SYM_OUTLINE"-400,850,400,-850"
CDS_LIB"mstr_controller"
PACK_TYPE"QFN"
SEC_TYPE"QFN"
SEC"1"
CDS_LOCATION"EU3P1";
"AVRRDY"
$PN"9"36;
"PINALRT_N \B"
$PN"12"0;
"THPAD"
$PN"41"4;
"BPWM1"
$PN"3"0;
"APWM1"
$PN"5"34;
"SDA"
$PN"6"39;
"SCL"
$PN"7"40;
"VCLK"
$PN"15"21;
"VDIO"
$PN"16"31;
"RESET_N \B"
$PN"8"0;
"XADDR1"
$PN"36"37;
"XADDR2"
$PN"33"20;
"ATSEN"
$PN"35"26;
"AISEN1"
$PN"22"23;
"AIREF1"
$PN"21"19;
"VDD"
$PN"39"44;
"BTSEN"
$PN"34"0;
"BISEN1"
$PN"26"12;
"BIREF1"
$PN"25"0;
"DNC<0>"
$PN"1"0;
"DNC<1>"
$PN"2"0;
"DNC<2>"
$PN"4"0;
"DNC<4>"
$PN"28"0;
"GND<0>"
$PN"27"4;
"GND<1>"
$PN"23"4;
"VRHOT_N \B"
$PN"11"25;
"VALRT_N \B"
$PN"17"24;
"AVSEN"
$PN"19"29;
"AVREF"
$PN"20"38;
"BVSEN"
$PN"29"0;
"BVREF"
$PN"30"0;
"VINSEN"
$PN"37"27;
"IINSEN"
$PN"38"0;
"VD12"
$PN"40"28;
"DNC<3>"
$PN"24"0;
"MP0"
$PN"13"0;
"MP1"
$PN"14"0;
"MP2"
$PN"18"0;
"MP3"
$PN"31"0;
"MP4"
$PN"32"35;
"AVREN"
$PN"10"22;
%"SC22P50V2JN-4GP"
"1","(-1975,3600)","1","w_hdl","I95";
;
CDS_SEC"1"
$SEC"1"
CDS_LOCATION"CF13"
GROUP"POWER_FAIR"
TOLERANCE"5%"
ATTRIBUTE"22PF"
TYPE"NPO"
VALUE"SC22P50V2JN-4GP"
LOCATION"CF13"
RATED"50V"
PACK_SIZE"0402"
CDS_LIB"w_hdl"
CDS_LMAN_SYM_OUTLINE"-50,25,50,-25"
PART_NUMBER"78.22034.1FL"
PACK_TYPE"SMD-BCG";
"2"
$PN"2"23;
"1"
$PN"1"19;
%"RES"
"1","(-1975,3750)","0","mstr_discrete","I96";
;
CDS_SEC"1"
CDS_LOCATION"RF13"
MATERIAL"CHIP"
VALUE"1.0K"
TOLERANCE"0.1%"
PART_NUMBER"G85996-004"
PACK_TYPE"0402"
WATTAGE"1/16W"
LOCATION"RF13"
GROUP"POWER_FAIR"
SEC_TYPE"0402"
SEC"1"
CDS_LIB"mstr_discrete"
ROOM"SB";
"B"
$PN"2"23;
"A"
$PN"1"19;
%"CAP"
"1","(-2250,2750)","0","mstr_discrete","I97";
;
PART_NUMBER"A36096-050"
PACK_TYPE"0402LF"
VOLTAGE"50V"
MATERIAL"X7R"
TOLERANCE"10%"
LOCATION"C4W1"
VALUE"220PF"
CDS_LOCATION"C4W1"
CDS_SEC"1"
CDS_LIB"mstr_discrete"
ROOM"PVCCIN_CPU0_VR"
SEC"1"
SEC_TYPE"0402LF";
"A"
$PN"1"26;
"B"
$PN"2"16;
%"GND"
"1","(-2250,2550)","0","mstr_symbols","I98";
;
HDL_POWER"GND"
BODY_TYPE"PLUMBING"
CDS_LIB"mstr_symbols"
VOLTAGE"0"
ROOM"PVCCIN_CPU0_VR"
SIZE"1B";
"A\NAC"16;
%"RES"
"2","(-2125,4525)","0","mstr_discrete","I99";
;
WATTAGE"1/16W"
LOCATION"R3P17"
TOLERANCE"1%"
MATERIAL"CHIP"
PART_NUMBER"G21796-047"
VALUE"49.9"
PACK_TYPE"0402"
CDS_SEC"1"
CDS_LIB"mstr_discrete"
SEC_TYPE"0402"
SEC"1"
ROOM"PVCCIN_CPU0_VR"
CDS_LOCATION"R3P17";
"A"
$PN"1"8;
"B"
$PN"2"17;
END.
